# T6G (Grand Teton) — schematic netlist excerpt (pin names and nets, part order shuffled) for the footprints in the layout excerpt that follows; sources: Cadence DE-HDL packaged netlist, KiCad conversion of 04192023_DAF0TMB3IC0_F0TG_MB_C_brd_V02_OCP.brd

U82  SN74LVC1G07DBVR  IC  pkg SMLF  page 166
  NC  = NC
  A  = BOOT_RDY_R1_N
  GND  = GND
  Y  = BOOT_RDY_BUF_R_LED
  VCC  = P1V8_AUX

R1251  Q_RES  0 5% CHIP  pkg 0402LF  page 258 : A = P1V2_AUX_ADC ; B = P1V2_AUX_ADC_TIC

(kicad_pcb
	(version 20260206)
	(generator "pcbnew")
	(generator_version "10.0")
	(general
		(thickness 1.6)
		(legacy_teardrops no)
	)
	(paper "A4")
	(title_block
		(title "04192023_DAF0TMB3IC0_F0TG_MB_C_brd_V02_OCP.brd")
		(comment 1 "Grand Teton / footprints 7565-7566 of 8354")
	)
	(layers
		(0 "F.Cu" signal "TOP")
		(4 "In1.Cu" signal "GND")
		(6 "In2.Cu" signal "IN1")
		(8 "In3.Cu" signal "GND1")
		(10 "In4.Cu" signal "IN2")
		(12 "In5.Cu" signal "GND2")
		(14 "In6.Cu" signal "IN3")
		(16 "In7.Cu" signal "GND3")
		(18 "In8.Cu" signal "VCC")
		(20 "In9.Cu" signal "VCC1")
		(22 "In10.Cu" signal "GND4")
		(24 "In11.Cu" signal "IN4")
		(26 "In12.Cu" signal "GND5")
		(28 "In13.Cu" signal "IN5")
		(30 "In14.Cu" signal "GND6")
		(32 "In15.Cu" signal "IN6")
		(34 "In16.Cu" signal "GND7")
		(2 "B.Cu" signal "BOTTOM")
		(9 "F.Adhes" user "F.Adhesive")
		(11 "B.Adhes" user "B.Adhesive")
		(13 "F.Paste" user "Package Geometry/Pastemask Top")
		(15 "B.Paste" user "Package Geometry/Pastemask Bottom")
		(5 "F.SilkS" user "Ref Des/Silkscreen Top")
		(7 "B.SilkS" user "Ref Des/Silkscreen Bottom")
		(1 "F.Mask" user "Board Geometry/Soldermask Top")
		(3 "B.Mask" user "Board Geometry/Soldermask Bottom")
		(17 "Dwgs.User" user "User.Drawings")
		(19 "Cmts.User" user "User.Comments")
		(21 "Eco1.User" user "User.Eco1")
		(23 "Eco2.User" user "User.Eco2")
		(25 "Edge.Cuts" user "Board Geometry/Outline")
		(27 "Margin" user)
		(31 "F.CrtYd" user "Package Geometry/Place Bound Top")
		(29 "B.CrtYd" user "Package Geometry/Place Bound Bottom")
		(35 "F.Fab" user "Ref Des/Assembly Top")
		(33 "B.Fab" user "Ref Des/Assembly Bottom")
	)
	(footprint ""
		(layer "B.Cu")
		(at 404.475696 -340.622382)
		(property "Reference" "U82"
			(at 5.969 -0.980948 0)
			(unlocked yes)
			(layer "B.SilkS")
			(effects
				(font
					(size 0.7874 0.5842)
					(thickness 0.1524)
				)
				(justify left mirror)
			)
		)
		(property "Value" ""
			(at 0 0 0)
			(layer "B.Fab")
			(effects
				(font
					(size 1.27 1.27)
				)
				(justify mirror)
			)
		)
		(duplicate_pad_numbers_are_jumpers no)
		(fp_line
			(start -2.0574 -1.651)
			(end -2.0574 1.651)
			(stroke
				(width 0.1524)
				(type default)
			)
			(layer "B.SilkS")
		)
		(fp_line
			(start -2.0574 1.651)
			(end 2.0574 1.651)
			(stroke
				(width 0.1524)
				(type default)
			)
			(layer "B.SilkS")
		)
		(fp_line
			(start -0.381 -1.651)
			(end -2.0574 -1.651)
			(stroke
				(width 0.1524)
				(type default)
			)
			(layer "B.SilkS")
		)
		(fp_line
			(start 0 -1.016)
			(end -0.381 -1.651)
			(stroke
				(width 0.1524)
				(type default)
			)
			(layer "B.SilkS")
		)
		(fp_line
			(start 0.381 -1.651)
			(end 0 -1.016)
			(stroke
				(width 0.1524)
				(type default)
			)
			(layer "B.SilkS")
		)
		(fp_line
			(start 2.0574 -1.651)
			(end 0.381 -1.651)
			(stroke
				(width 0.1524)
				(type default)
			)
			(layer "B.SilkS")
		)
		(fp_line
			(start 2.0574 1.651)
			(end 2.0574 -1.651)
			(stroke
				(width 0.1524)
				(type default)
			)
			(layer "B.SilkS")
		)
		(fp_poly
			(pts
				(xy 2.159 -1.016) (xy 2.71272 -0.719328) (xy 2.71272 -1.344168)
			)
			(stroke
				(width 0)
				(type default)
			)
			(fill yes)
			(layer "B.SilkS")
		)
		(fp_line
			(start -1.599946 -1.199896)
			(end -1.599946 1.199896)
			(stroke
				(width 0.1)
				(type default)
			)
			(layer "B.Fab")
		)
		(fp_line
			(start -1.599946 1.199896)
			(end -0.899922 1.199896)
			(stroke
				(width 0.1)
				(type default)
			)
			(layer "B.Fab")
		)
		(fp_line
			(start -0.899922 -1.549908)
			(end -0.899922 -1.199896)
			(stroke
				(width 0.1)
				(type default)
			)
			(layer "B.Fab")
		)
		(fp_line
			(start -0.899922 -1.199896)
			(end -1.599946 -1.199896)
			(stroke
				(width 0.1)
				(type default)
			)
			(layer "B.Fab")
		)
		(fp_line
			(start -0.899922 1.199896)
			(end -0.899922 1.549908)
			(stroke
				(width 0.1)
				(type default)
			)
			(layer "B.Fab")
		)
		(fp_line
			(start -0.899922 1.549908)
			(end 0.899922 1.549908)
			(stroke
				(width 0.1)
				(type default)
			)
			(layer "B.Fab")
		)
		(fp_line
			(start 0.899922 -1.549908)
			(end -0.899922 -1.549908)
			(stroke
				(width 0.1)
				(type default)
			)
			(layer "B.Fab")
		)
		(fp_line
			(start 0.899922 -1.199896)
			(end 0.899922 -1.549908)
			(stroke
				(width 0.1)
				(type default)
			)
			(layer "B.Fab")
		)
		(fp_line
			(start 0.899922 1.199896)
			(end 1.599946 1.199896)
			(stroke
				(width 0.1)
				(type default)
			)
			(layer "B.Fab")
		)
		(fp_line
			(start 0.899922 1.549908)
			(end 0.899922 1.199896)
			(stroke
				(width 0.1)
				(type default)
			)
			(layer "B.Fab")
		)
		(fp_line
			(start 1.599946 -1.199896)
			(end 0.899922 -1.199896)
			(stroke
				(width 0.1)
				(type default)
			)
			(layer "B.Fab")
		)
		(fp_line
			(start 1.599946 1.199896)
			(end 1.599946 -1.199896)
			(stroke
				(width 0.1)
				(type default)
			)
			(layer "B.Fab")
		)
		(fp_poly
			(pts
				(xy 2.71272 -0.719328) (xy 2.71272 -1.344168) (xy 2.159 -1.016)
			)
			(stroke
				(width 0)
				(type default)
			)
			(fill yes)
			(layer "B.Fab")
		)
		(pad "1" smd rect
			(at 1.225042 -0.94996 270)
			(size 0.5588 1.3462)
			(layers "B.Cu" "B.Mask" "B.Paste")
			(net "Net_10732")
		)
		(pad "2" smd rect
			(at 1.225042 0 270)
			(size 0.5588 1.3462)
			(layers "B.Cu" "B.Mask" "B.Paste")
			(net "BOOT_RDY_R1_N")
		)
		(pad "3" smd rect
			(at 1.225042 0.94996 270)
			(size 0.5588 1.3462)
			(layers "B.Cu" "B.Mask" "B.Paste")
			(net "GND")
		)
		(pad "4" smd rect
			(at -1.225042 0.94996 270)
			(size 0.5588 1.3462)
			(layers "B.Cu" "B.Mask" "B.Paste")
			(net "BOOT_RDY_BUF_R_LED")
		)
		(pad "5" smd rect
			(at -1.225042 -0.94996 270)
			(size 0.5588 1.3462)
			(layers "B.Cu" "B.Mask" "B.Paste")
			(net "P1V8_AUX")
		)
	)
	(footprint ""
		(layer "B.Cu")
		(at 231.074722 -323.913754)
		(property "Reference" "R1251"
			(at 0 0 0)
			(layer "B.SilkS")
			(hide yes)
			(effects
				(font
					(size 1.27 1.27)
				)
				(justify mirror)
			)
		)
		(property "Value" ""
			(at 0 0 0)
			(layer "B.Fab")
			(effects
				(font
					(size 1.27 1.27)
				)
				(justify mirror)
			)
		)
		(duplicate_pad_numbers_are_jumpers no)
		(fp_line
			(start -0.7874 -0.4064)
			(end -0.7874 0.4064)
			(stroke
				(width 0.1524)
				(type default)
			)
			(layer "B.SilkS")
		)
		(fp_line
			(start -0.7874 0.4064)
			(end 0.7874 0.4064)
			(stroke
				(width 0.1524)
				(type default)
			)
			(layer "B.SilkS")
		)
		(fp_line
			(start 0.7874 -0.4064)
			(end -0.7874 -0.4064)
			(stroke
				(width 0.1524)
				(type default)
			)
			(layer "B.SilkS")
		)
		(fp_line
			(start 0.7874 0.4064)
			(end 0.7874 -0.4064)
			(stroke
				(width 0.1524)
				(type default)
			)
			(layer "B.SilkS")
		)
		(fp_line
			(start -0.67945 -0.3048)
			(end -0.67945 0.3048)
			(stroke
				(width 0.1)
				(type default)
			)
			(layer "B.Fab")
		)
		(fp_line
			(start -0.67945 0.3048)
			(end -0.120396 0.3048)
			(stroke
				(width 0.1)
				(type default)
			)
			(layer "B.Fab")
		)
		(fp_line
			(start -0.12065 -0.3048)
			(end -0.67945 -0.3048)
			(stroke
				(width 0.1)
				(type default)
			)
			(layer "B.Fab")
		)
		(fp_line
			(start -0.12065 -0.2794)
			(end -0.12065 -0.3048)
			(stroke
				(width 0.1)
				(type default)
			)
			(layer "B.Fab")
		)
		(fp_line
			(start -0.120396 0.2794)
			(end 0.12065 0.2794)
			(stroke
				(width 0.1)
				(type default)
			)
			(layer "B.Fab")
		)
		(fp_line
			(start -0.120396 0.3048)
			(end -0.120396 0.2794)
			(stroke
				(width 0.1)
				(type default)
			)
			(layer "B.Fab")
		)
		(fp_line
			(start 0.12065 -0.305054)
			(end 0.12065 -0.2794)
			(stroke
				(width 0.1)
				(type default)
			)
			(layer "B.Fab")
		)
		(fp_line
			(start 0.12065 -0.2794)
			(end -0.12065 -0.2794)
			(stroke
				(width 0.1)
				(type default)
			)
			(layer "B.Fab")
		)
		(fp_line
			(start 0.12065 0.2794)
			(end 0.12065 0.3048)
			(stroke
				(width 0.1)
				(type default)
			)
			(layer "B.Fab")
		)
		(fp_line
			(start 0.12065 0.3048)
			(end 0.67945 0.3048)
			(stroke
				(width 0.1)
				(type default)
			)
			(layer "B.Fab")
		)
		(fp_line
			(start 0.67945 -0.305054)
			(end 0.12065 -0.305054)
			(stroke
				(width 0.1)
				(type default)
			)
			(layer "B.Fab")
		)
		(fp_line
			(start 0.67945 0.3048)
			(end 0.67945 -0.305054)
			(stroke
				(width 0.1)
				(type default)
			)
			(layer "B.Fab")
		)
		(pad "1" smd rect
			(at 0.40005 0)
			(size 0.4572 0.508)
			(layers "B.Cu" "B.Mask" "B.Paste")
			(net "P1V2_AUX_ADC")
		)
		(pad "2" smd rect
			(at -0.40005 0)
			(size 0.4572 0.508)
			(layers "B.Cu" "B.Mask" "B.Paste")
			(net "P1V2_AUX_ADC_TIC")
		)
	)
)
